(kicad_pcb
	(version 20260206)
	(generator "pcbnew")
	(generator_version "10.0")
	(general
		(thickness 1.6)
		(legacy_teardrops no)
	)
	(paper "A4")
	(title_block
		(title "03242023_DA0F0TMBIJ0_F0T_Motherboard_J_brd_V01_OCP.brd")
		(comment 1 "Grand Teton / footprints 5106-5111 of 6105")
	)
	(layers
		(0 "F.Cu" signal "TOP")
		(4 "In1.Cu" signal "GND")
		(6 "In2.Cu" signal "IN1")
		(8 "In3.Cu" signal "GND1")
		(10 "In4.Cu" signal "IN2")
		(12 "In5.Cu" signal "GND2")
		(14 "In6.Cu" signal "IN3")
		(16 "In7.Cu" signal "GND3")
		(18 "In8.Cu" signal "VCC")
		(20 "In9.Cu" signal "VCC1")
		(22 "In10.Cu" signal "GND4")
		(24 "In11.Cu" signal "IN4")
		(26 "In12.Cu" signal "GND5")
		(28 "In13.Cu" signal "IN5")
		(30 "In14.Cu" signal "GND6")
		(32 "In15.Cu" signal "IN6")
		(34 "In16.Cu" signal "GND7")
		(2 "B.Cu" signal "BOTTOM")
		(9 "F.Adhes" user "F.Adhesive")
		(11 "B.Adhes" user "B.Adhesive")
		(13 "F.Paste" user "Package Geometry/Pastemask Top")
		(15 "B.Paste" user "Package Geometry/Pastemask Bottom")
		(5 "F.SilkS" user "Ref Des/Silkscreen Top")
		(7 "B.SilkS" user "Ref Des/Silkscreen Bottom")
		(1 "F.Mask" user "Board Geometry/Soldermask Top")
		(3 "B.Mask" user "Board Geometry/Soldermask Bottom")
		(17 "Dwgs.User" user "User.Drawings")
		(19 "Cmts.User" user "User.Comments")
		(21 "Eco1.User" user "User.Eco1")
		(23 "Eco2.User" user "User.Eco2")
		(25 "Edge.Cuts" user "Board Geometry/Outline")
		(27 "Margin" user)
		(31 "F.CrtYd" user "Package Geometry/Place Bound Top")
		(29 "B.CrtYd" user "Package Geometry/Place Bound Bottom")
		(35 "F.Fab" user "Ref Des/Assembly Top")
		(33 "B.Fab" user "Ref Des/Assembly Bottom")
	)
	(footprint ""
		(layer "B.Cu")
		(at 373.143018 -186.14517 -90)
		(property "Reference" "R911"
			(at 0 0 90)
			(layer "B.SilkS")
			(hide yes)
			(effects
				(font
					(size 1.27 1.27)
				)
				(justify mirror)
			)
		)
		(property "Value" ""
			(at 0 0 90)
			(layer "B.Fab")
			(effects
				(font
					(size 1.27 1.27)
				)
				(justify mirror)
			)
		)
		(duplicate_pad_numbers_are_jumpers no)
		(fp_line
			(start -0.7874 0.4064)
			(end 0.7874 0.4064)
			(stroke
				(width 0.1524)
				(type default)
			)
			(layer "B.SilkS")
		)
		(fp_line
			(start 0.7874 0.4064)
			(end 0.7874 -0.4064)
			(stroke
				(width 0.1524)
				(type default)
			)
			(layer "B.SilkS")
		)
		(fp_line
			(start -0.7874 -0.4064)
			(end -0.7874 0.4064)
			(stroke
				(width 0.1524)
				(type default)
			)
			(layer "B.SilkS")
		)
		(fp_line
			(start 0.7874 -0.4064)
			(end -0.7874 -0.4064)
			(stroke
				(width 0.1524)
				(type default)
			)
			(layer "B.SilkS")
		)
		(fp_line
			(start -0.67945 0.3048)
			(end -0.120396 0.3048)
			(stroke
				(width 0.1)
				(type default)
			)
			(layer "B.Fab")
		)
		(fp_line
			(start -0.120396 0.3048)
			(end -0.120396 0.2794)
			(stroke
				(width 0.1)
				(type default)
			)
			(layer "B.Fab")
		)
		(fp_line
			(start 0.12065 0.3048)
			(end 0.67945 0.3048)
			(stroke
				(width 0.1)
				(type default)
			)
			(layer "B.Fab")
		)
		(fp_line
			(start 0.67945 0.3048)
			(end 0.67945 -0.305054)
			(stroke
				(width 0.1)
				(type default)
			)
			(layer "B.Fab")
		)
		(fp_line
			(start -0.120396 0.2794)
			(end 0.12065 0.2794)
			(stroke
				(width 0.1)
				(type default)
			)
			(layer "B.Fab")
		)
		(fp_line
			(start 0.12065 0.2794)
			(end 0.12065 0.3048)
			(stroke
				(width 0.1)
				(type default)
			)
			(layer "B.Fab")
		)
		(fp_line
			(start -0.12065 -0.2794)
			(end -0.12065 -0.3048)
			(stroke
				(width 0.1)
				(type default)
			)
			(layer "B.Fab")
		)
		(fp_line
			(start 0.12065 -0.2794)
			(end -0.12065 -0.2794)
			(stroke
				(width 0.1)
				(type default)
			)
			(layer "B.Fab")
		)
		(fp_line
			(start -0.67945 -0.3048)
			(end -0.67945 0.3048)
			(stroke
				(width 0.1)
				(type default)
			)
			(layer "B.Fab")
		)
		(fp_line
			(start -0.12065 -0.3048)
			(end -0.67945 -0.3048)
			(stroke
				(width 0.1)
				(type default)
			)
			(layer "B.Fab")
		)
		(fp_line
			(start 0.12065 -0.305054)
			(end 0.12065 -0.2794)
			(stroke
				(width 0.1)
				(type default)
			)
			(layer "B.Fab")
		)
		(fp_line
			(start 0.67945 -0.305054)
			(end 0.12065 -0.305054)
			(stroke
				(width 0.1)
				(type default)
			)
			(layer "B.Fab")
		)
		(pad "1" smd circle
			(at 0.40005 0 90)
			(size 0 0)
			(layers "B.Cu" "B.Mask" "B.Paste")
			(net "PVNN_TERM_CPU0")
		)
		(pad "2" smd circle
			(at -0.40005 0 90)
			(size 0 0)
			(layers "B.Cu" "B.Mask" "B.Paste")
			(net "SMB_PEHPCPU0_GTL_R_SDA")
		)
	)
	(footprint ""
		(layer "B.Cu")
		(at 350.849438 -334.845152 -90)
		(property "Reference" "PR152"
			(at 0 0 90)
			(layer "B.SilkS")
			(hide yes)
			(effects
				(font
					(size 1.27 1.27)
				)
				(justify mirror)
			)
		)
		(property "Value" ""
			(at 0 0 90)
			(layer "B.Fab")
			(effects
				(font
					(size 1.27 1.27)
				)
				(justify mirror)
			)
		)
		(duplicate_pad_numbers_are_jumpers no)
		(fp_line
			(start -0.7874 0.4064)
			(end 0.7874 0.4064)
			(stroke
				(width 0.1524)
				(type default)
			)
			(layer "B.SilkS")
		)
		(fp_line
			(start 0.7874 0.4064)
			(end 0.7874 -0.4064)
			(stroke
				(width 0.1524)
				(type default)
			)
			(layer "B.SilkS")
		)
		(fp_line
			(start -0.7874 -0.4064)
			(end -0.7874 0.4064)
			(stroke
				(width 0.1524)
				(type default)
			)
			(layer "B.SilkS")
		)
		(fp_line
			(start 0.7874 -0.4064)
			(end -0.7874 -0.4064)
			(stroke
				(width 0.1524)
				(type default)
			)
			(layer "B.SilkS")
		)
		(fp_line
			(start -0.67945 0.3048)
			(end -0.120396 0.3048)
			(stroke
				(width 0.1)
				(type default)
			)
			(layer "B.Fab")
		)
		(fp_line
			(start -0.120396 0.3048)
			(end -0.120396 0.2794)
			(stroke
				(width 0.1)
				(type default)
			)
			(layer "B.Fab")
		)
		(fp_line
			(start 0.12065 0.3048)
			(end 0.67945 0.3048)
			(stroke
				(width 0.1)
				(type default)
			)
			(layer "B.Fab")
		)
		(fp_line
			(start 0.67945 0.3048)
			(end 0.67945 -0.305054)
			(stroke
				(width 0.1)
				(type default)
			)
			(layer "B.Fab")
		)
		(fp_line
			(start -0.120396 0.2794)
			(end 0.12065 0.2794)
			(stroke
				(width 0.1)
				(type default)
			)
			(layer "B.Fab")
		)
		(fp_line
			(start 0.12065 0.2794)
			(end 0.12065 0.3048)
			(stroke
				(width 0.1)
				(type default)
			)
			(layer "B.Fab")
		)
		(fp_line
			(start -0.12065 -0.2794)
			(end -0.12065 -0.3048)
			(stroke
				(width 0.1)
				(type default)
			)
			(layer "B.Fab")
		)
		(fp_line
			(start 0.12065 -0.2794)
			(end -0.12065 -0.2794)
			(stroke
				(width 0.1)
				(type default)
			)
			(layer "B.Fab")
		)
		(fp_line
			(start -0.67945 -0.3048)
			(end -0.67945 0.3048)
			(stroke
				(width 0.1)
				(type default)
			)
			(layer "B.Fab")
		)
		(fp_line
			(start -0.12065 -0.3048)
			(end -0.67945 -0.3048)
			(stroke
				(width 0.1)
				(type default)
			)
			(layer "B.Fab")
		)
		(fp_line
			(start 0.12065 -0.305054)
			(end 0.12065 -0.2794)
			(stroke
				(width 0.1)
				(type default)
			)
			(layer "B.Fab")
		)
		(fp_line
			(start 0.67945 -0.305054)
			(end 0.12065 -0.305054)
			(stroke
				(width 0.1)
				(type default)
			)
			(layer "B.Fab")
		)
		(pad "1" smd circle
			(at 0.40005 0 90)
			(size 0 0)
			(layers "B.Cu" "B.Mask" "B.Paste")
			(net "PVCCIN_CPU0_PVCC")
		)
		(pad "2" smd circle
			(at -0.40005 0 90)
			(size 0 0)
			(layers "B.Cu" "B.Mask" "B.Paste")
			(net "PVCCIN_CPU0_VDD2")
		)
	)
	(footprint ""
		(layer "B.Cu")
		(at 120.145302 -262.032496 -90)
		(property "Reference" "C490"
			(at 0 0 90)
			(layer "B.SilkS")
			(hide yes)
			(effects
				(font
					(size 1.27 1.27)
				)
				(justify mirror)
			)
		)
		(property "Value" ""
			(at 0 0 90)
			(layer "B.Fab")
			(effects
				(font
					(size 1.27 1.27)
				)
				(justify mirror)
			)
		)
		(duplicate_pad_numbers_are_jumpers no)
		(fp_line
			(start -0.7874 0.4064)
			(end 0.7874 0.4064)
			(stroke
				(width 0.1524)
				(type default)
			)
			(layer "B.SilkS")
		)
		(fp_line
			(start 0.7874 0.4064)
			(end 0.7874 -0.4064)
			(stroke
				(width 0.1524)
				(type default)
			)
			(layer "B.SilkS")
		)
		(fp_line
			(start -0.7874 -0.4064)
			(end -0.7874 0.4064)
			(stroke
				(width 0.1524)
				(type default)
			)
			(layer "B.SilkS")
		)
		(fp_line
			(start 0.7874 -0.4064)
			(end -0.7874 -0.4064)
			(stroke
				(width 0.1524)
				(type default)
			)
			(layer "B.SilkS")
		)
		(fp_line
			(start -0.67945 0.3048)
			(end -0.120396 0.3048)
			(stroke
				(width 0.1)
				(type default)
			)
			(layer "B.Fab")
		)
		(fp_line
			(start -0.120396 0.3048)
			(end -0.120396 0.2794)
			(stroke
				(width 0.1)
				(type default)
			)
			(layer "B.Fab")
		)
		(fp_line
			(start 0.12065 0.3048)
			(end 0.67945 0.3048)
			(stroke
				(width 0.1)
				(type default)
			)
			(layer "B.Fab")
		)
		(fp_line
			(start 0.67945 0.3048)
			(end 0.67945 -0.305054)
			(stroke
				(width 0.1)
				(type default)
			)
			(layer "B.Fab")
		)
		(fp_line
			(start -0.120396 0.2794)
			(end 0.12065 0.2794)
			(stroke
				(width 0.1)
				(type default)
			)
			(layer "B.Fab")
		)
		(fp_line
			(start 0.12065 0.2794)
			(end 0.12065 0.3048)
			(stroke
				(width 0.1)
				(type default)
			)
			(layer "B.Fab")
		)
		(fp_line
			(start -0.12065 -0.2794)
			(end -0.12065 -0.3048)
			(stroke
				(width 0.1)
				(type default)
			)
			(layer "B.Fab")
		)
		(fp_line
			(start 0.12065 -0.2794)
			(end -0.12065 -0.2794)
			(stroke
				(width 0.1)
				(type default)
			)
			(layer "B.Fab")
		)
		(fp_line
			(start -0.67945 -0.3048)
			(end -0.67945 0.3048)
			(stroke
				(width 0.1)
				(type default)
			)
			(layer "B.Fab")
		)
		(fp_line
			(start -0.12065 -0.3048)
			(end -0.67945 -0.3048)
			(stroke
				(width 0.1)
				(type default)
			)
			(layer "B.Fab")
		)
		(fp_line
			(start 0.12065 -0.305054)
			(end 0.12065 -0.2794)
			(stroke
				(width 0.1)
				(type default)
			)
			(layer "B.Fab")
		)
		(fp_line
			(start 0.67945 -0.305054)
			(end 0.12065 -0.305054)
			(stroke
				(width 0.1)
				(type default)
			)
			(layer "B.Fab")
		)
		(pad "1" smd circle
			(at 0.40005 0 90)
			(size 0 0)
			(layers "B.Cu" "B.Mask" "B.Paste")
			(net "PVCCINFAON_CPU1")
		)
		(pad "2" smd circle
			(at -0.40005 0 90)
			(size 0 0)
			(layers "B.Cu" "B.Mask" "B.Paste")
			(net "GND")
		)
	)
	(footprint ""
		(layer "B.Cu")
		(at 431.72888 -124.932948 90)
		(property "Reference" "PR4234"
			(at 0 0 90)
			(layer "B.SilkS")
			(hide yes)
			(effects
				(font
					(size 1.27 1.27)
				)
				(justify mirror)
			)
		)
		(property "Value" ""
			(at 0 0 90)
			(layer "B.Fab")
			(effects
				(font
					(size 1.27 1.27)
				)
				(justify mirror)
			)
		)
		(duplicate_pad_numbers_are_jumpers no)
		(fp_line
			(start 0.7874 -0.4064)
			(end -0.7874 -0.4064)
			(stroke
				(width 0.1524)
				(type default)
			)
			(layer "B.SilkS")
		)
		(fp_line
			(start -0.7874 -0.4064)
			(end -0.7874 0.4064)
			(stroke
				(width 0.1524)
				(type default)
			)
			(layer "B.SilkS")
		)
		(fp_line
			(start 0.7874 0.4064)
			(end 0.7874 -0.4064)
			(stroke
				(width 0.1524)
				(type default)
			)
			(layer "B.SilkS")
		)
		(fp_line
			(start -0.7874 0.4064)
			(end 0.7874 0.4064)
			(stroke
				(width 0.1524)
				(type default)
			)
			(layer "B.SilkS")
		)
		(fp_line
			(start 0.67945 -0.305054)
			(end 0.12065 -0.305054)
			(stroke
				(width 0.1)
				(type default)
			)
			(layer "B.Fab")
		)
		(fp_line
			(start 0.12065 -0.305054)
			(end 0.12065 -0.2794)
			(stroke
				(width 0.1)
				(type default)
			)
			(layer "B.Fab")
		)
		(fp_line
			(start -0.12065 -0.3048)
			(end -0.67945 -0.3048)
			(stroke
				(width 0.1)
				(type default)
			)
			(layer "B.Fab")
		)
		(fp_line
			(start -0.67945 -0.3048)
			(end -0.67945 0.3048)
			(stroke
				(width 0.1)
				(type default)
			)
			(layer "B.Fab")
		)
		(fp_line
			(start 0.12065 -0.2794)
			(end -0.12065 -0.2794)
			(stroke
				(width 0.1)
				(type default)
			)
			(layer "B.Fab")
		)
		(fp_line
			(start -0.12065 -0.2794)
			(end -0.12065 -0.3048)
			(stroke
				(width 0.1)
				(type default)
			)
			(layer "B.Fab")
		)
		(fp_line
			(start 0.12065 0.2794)
			(end 0.12065 0.3048)
			(stroke
				(width 0.1)
				(type default)
			)
			(layer "B.Fab")
		)
		(fp_line
			(start -0.120396 0.2794)
			(end 0.12065 0.2794)
			(stroke
				(width 0.1)
				(type default)
			)
			(layer "B.Fab")
		)
		(fp_line
			(start 0.67945 0.3048)
			(end 0.67945 -0.305054)
			(stroke
				(width 0.1)
				(type default)
			)
			(layer "B.Fab")
		)
		(fp_line
			(start 0.12065 0.3048)
			(end 0.67945 0.3048)
			(stroke
				(width 0.1)
				(type default)
			)
			(layer "B.Fab")
		)
		(fp_line
			(start -0.120396 0.3048)
			(end -0.120396 0.2794)
			(stroke
				(width 0.1)
				(type default)
			)
			(layer "B.Fab")
		)
		(fp_line
			(start -0.67945 0.3048)
			(end -0.120396 0.3048)
			(stroke
				(width 0.1)
				(type default)
			)
			(layer "B.Fab")
		)
		(pad "1" smd circle
			(at 0.40005 0 270)
			(size 0 0)
			(layers "B.Cu" "B.Mask" "B.Paste")
			(net "NC_PVCCD_HV_CPU0_ACSP6")
		)
		(pad "2" smd circle
			(at -0.40005 0 270)
			(size 0 0)
			(layers "B.Cu" "B.Mask" "B.Paste")
			(net "GND")
		)
	)
	(footprint ""
		(layer "B.Cu")
		(at 432.523392 -193.565272 -90)
		(property "Reference" "C621"
			(at 0 0 90)
			(layer "B.SilkS")
			(hide yes)
			(effects
				(font
					(size 1.27 1.27)
				)
				(justify mirror)
			)
		)
		(property "Value" ""
			(at 0 0 90)
			(layer "B.Fab")
			(effects
				(font
					(size 1.27 1.27)
				)
				(justify mirror)
			)
		)
		(duplicate_pad_numbers_are_jumpers no)
		(fp_line
			(start -0.7874 0.4064)
			(end 0.7874 0.4064)
			(stroke
				(width 0.1524)
				(type default)
			)
			(layer "B.SilkS")
		)
		(fp_line
			(start 0.7874 0.4064)
			(end 0.7874 -0.4064)
			(stroke
				(width 0.1524)
				(type default)
			)
			(layer "B.SilkS")
		)
		(fp_line
			(start -0.7874 -0.4064)
			(end -0.7874 0.4064)
			(stroke
				(width 0.1524)
				(type default)
			)
			(layer "B.SilkS")
		)
		(fp_line
			(start 0.7874 -0.4064)
			(end -0.7874 -0.4064)
			(stroke
				(width 0.1524)
				(type default)
			)
			(layer "B.SilkS")
		)
		(fp_line
			(start -0.67945 0.3048)
			(end -0.120396 0.3048)
			(stroke
				(width 0.1)
				(type default)
			)
			(layer "B.Fab")
		)
		(fp_line
			(start -0.120396 0.3048)
			(end -0.120396 0.2794)
			(stroke
				(width 0.1)
				(type default)
			)
			(layer "B.Fab")
		)
		(fp_line
			(start 0.12065 0.3048)
			(end 0.67945 0.3048)
			(stroke
				(width 0.1)
				(type default)
			)
			(layer "B.Fab")
		)
		(fp_line
			(start 0.67945 0.3048)
			(end 0.67945 -0.305054)
			(stroke
				(width 0.1)
				(type default)
			)
			(layer "B.Fab")
		)
		(fp_line
			(start -0.120396 0.2794)
			(end 0.12065 0.2794)
			(stroke
				(width 0.1)
				(type default)
			)
			(layer "B.Fab")
		)
		(fp_line
			(start 0.12065 0.2794)
			(end 0.12065 0.3048)
			(stroke
				(width 0.1)
				(type default)
			)
			(layer "B.Fab")
		)
		(fp_line
			(start -0.12065 -0.2794)
			(end -0.12065 -0.3048)
			(stroke
				(width 0.1)
				(type default)
			)
			(layer "B.Fab")
		)
		(fp_line
			(start 0.12065 -0.2794)
			(end -0.12065 -0.2794)
			(stroke
				(width 0.1)
				(type default)
			)
			(layer "B.Fab")
		)
		(fp_line
			(start -0.67945 -0.3048)
			(end -0.67945 0.3048)
			(stroke
				(width 0.1)
				(type default)
			)
			(layer "B.Fab")
		)
		(fp_line
			(start -0.12065 -0.3048)
			(end -0.67945 -0.3048)
			(stroke
				(width 0.1)
				(type default)
			)
			(layer "B.Fab")
		)
		(fp_line
			(start 0.12065 -0.305054)
			(end 0.12065 -0.2794)
			(stroke
				(width 0.1)
				(type default)
			)
			(layer "B.Fab")
		)
		(fp_line
			(start 0.67945 -0.305054)
			(end 0.12065 -0.305054)
			(stroke
				(width 0.1)
				(type default)
			)
			(layer "B.Fab")
		)
		(pad "1" smd circle
			(at 0.40005 0 90)
			(size 0 0)
			(layers "B.Cu" "B.Mask" "B.Paste")
			(net "RST_PLD_CPU0_DRAM_GH_N")
		)
		(pad "2" smd circle
			(at -0.40005 0 90)
			(size 0 0)
			(layers "B.Cu" "B.Mask" "B.Paste")
			(net "GND")
		)
	)
	(footprint ""
		(layer "B.Cu")
		(at 410.156152 -193.08953 -90)
		(property "Reference" "R281"
			(at 0 0 90)
			(layer "B.SilkS")
			(hide yes)
			(effects
				(font
					(size 1.27 1.27)
				)
				(justify mirror)
			)
		)
		(property "Value" ""
			(at 0 0 90)
			(layer "B.Fab")
			(effects
				(font
					(size 1.27 1.27)
				)
				(justify mirror)
			)
		)
		(duplicate_pad_numbers_are_jumpers no)
		(fp_line
			(start -0.7874 0.4064)
			(end 0.7874 0.4064)
			(stroke
				(width 0.1524)
				(type default)
			)
			(layer "B.SilkS")
		)
		(fp_line
			(start 0.7874 0.4064)
			(end 0.7874 -0.4064)
			(stroke
				(width 0.1524)
				(type default)
			)
			(layer "B.SilkS")
		)
		(fp_line
			(start -0.7874 -0.4064)
			(end -0.7874 0.4064)
			(stroke
				(width 0.1524)
				(type default)
			)
			(layer "B.SilkS")
		)
		(fp_line
			(start 0.7874 -0.4064)
			(end -0.7874 -0.4064)
			(stroke
				(width 0.1524)
				(type default)
			)
			(layer "B.SilkS")
		)
		(fp_line
			(start -0.67945 0.3048)
			(end -0.120396 0.3048)
			(stroke
				(width 0.1)
				(type default)
			)
			(layer "B.Fab")
		)
		(fp_line
			(start -0.120396 0.3048)
			(end -0.120396 0.2794)
			(stroke
				(width 0.1)
				(type default)
			)
			(layer "B.Fab")
		)
		(fp_line
			(start 0.12065 0.3048)
			(end 0.67945 0.3048)
			(stroke
				(width 0.1)
				(type default)
			)
			(layer "B.Fab")
		)
		(fp_line
			(start 0.67945 0.3048)
			(end 0.67945 -0.305054)
			(stroke
				(width 0.1)
				(type default)
			)
			(layer "B.Fab")
		)
		(fp_line
			(start -0.120396 0.2794)
			(end 0.12065 0.2794)
			(stroke
				(width 0.1)
				(type default)
			)
			(layer "B.Fab")
		)
		(fp_line
			(start 0.12065 0.2794)
			(end 0.12065 0.3048)
			(stroke
				(width 0.1)
				(type default)
			)
			(layer "B.Fab")
		)
		(fp_line
			(start -0.12065 -0.2794)
			(end -0.12065 -0.3048)
			(stroke
				(width 0.1)
				(type default)
			)
			(layer "B.Fab")
		)
		(fp_line
			(start 0.12065 -0.2794)
			(end -0.12065 -0.2794)
			(stroke
				(width 0.1)
				(type default)
			)
			(layer "B.Fab")
		)
		(fp_line
			(start -0.67945 -0.3048)
			(end -0.67945 0.3048)
			(stroke
				(width 0.1)
				(type default)
			)
			(layer "B.Fab")
		)
		(fp_line
			(start -0.12065 -0.3048)
			(end -0.67945 -0.3048)
			(stroke
				(width 0.1)
				(type default)
			)
			(layer "B.Fab")
		)
		(fp_line
			(start 0.12065 -0.305054)
			(end 0.12065 -0.2794)
			(stroke
				(width 0.1)
				(type default)
			)
			(layer "B.Fab")
		)
		(fp_line
			(start 0.67945 -0.305054)
			(end 0.12065 -0.305054)
			(stroke
				(width 0.1)
				(type default)
			)
			(layer "B.Fab")
		)
		(pad "1" smd circle
			(at 0.40005 0 90)
			(size 0 0)
			(layers "B.Cu" "B.Mask" "B.Paste")
			(net "PVNN_TERM_CPU0")
		)
		(pad "2" smd circle
			(at -0.40005 0 90)
			(size 0 0)
			(layers "B.Cu" "B.Mask" "B.Paste")
			(net "PU_CPU0_SOCKET_ID2")
		)
	)
)
